FILE_TYPE = MACRO_DRAWING;
SET COLOR_WIRE YELLOW;
SET COLOR_PROP ORANGE;
SET COLOR_DOT WHITE;
SET COLOR_ARC YELLOW;
SET COLOR_BODY GREEN;
SET COLOR_NOTE PURPLE;
SET PROP_DISPLAY VALUE;
SET PAGE_NUMBER P129;
FORCEADD QUANTA_TITLE_BLOCK_C..1
(0 0);
FORCEPROP 1 LAST CUSTOM_TXT_CDS <NAME_2>
J 0
(-3175 50);
FORCEPROP 1 LAST CUSTOM_TXT_CDS <NAME_1>
J 0
(-3175 175);
FORCEPROP 1 LAST CUSTOM_TXT_CDS <Q_NUMBER>
J 0
(-1403 103);
DISPLAY 1.212766 (-1403 103);
FORCEPROP 1 LAST CUSTOM_TXT_CDS <Q_PROJ>
J 0
(-2382 102);
DISPLAY 1.212766 (-2382 102);
FORCEPROP 1 LAST CUSTOM_TXT_CDS <Q_REV>
J 0
(-184 103);
DISPLAY 1.212766 (-184 103);
FORCEPROP 1 LAST CUSTOM_TXT_CDS <CON_LAST_MODIFIED>
J 0
(-1885 15);
DISPLAY 0.978723 (-1885 15);
FORCEPROP 1 LAST CUSTOM_TXT_CDS <CON_PAGE_NUM> OF <CON_TOTAL_PAGES>
J 0
(-446 18);
DISPLAY 0.978723 (-446 18);
FORCEPROP 1 LAST Q_DEPT BU9
J 1
(-3763 49);
DISPLAY 1.957447 (-3763 49);
PAINT GREEN (-3763 49);
FORCEPROP 1 LAST Q_TITLE M.2 CONN (2/2)
J 0
(-9366 26);
DISPLAY 2.446809 (-9366 26);
PAINT GREEN (-9366 26);
FORCEPROP 2 LAST PAGE_BORDER TRUE
J 0
(-7890 5250);
DISPLAY 0.638298 (-7890 5250);
PAINT PINK (-7890 5250);
DISPLAY INVISIBLE (-7890 5250);
FORCEPROP 2 LAST CDS_LIB pure_quanta
J 0
(0 0);
DISPLAY INVISIBLE (0 0);
FORCEPROP 1 LAST CDS_LMAN_SYM_OUTLINE -9475,6775,100,-125
J 0
(0 0);
DISPLAY 0.468085 (0 0);
PAINT GREEN (0 0);
DISPLAY INVISIBLE (0 0);
FORCEPROP 1 LAST COMMENT_BODY TRUE
J 0
(12 -13);
DISPLAY 0.978723 (12 -13);
PAINT GREEN (12 -13);
DISPLAY INVISIBLE (12 -13);
FORCEPROP 2 LAST CDS_XR_PAGE_TITLE CR-129 : @T6G_MB_LIB.T6G(SCH_1):PAGE129
J 0
(-7890 5250);
DISPLAY 0.638298 (-7890 5250);
PAINT PINK (-7890 5250);
DISPLAY INVISIBLE (-7890 5250);
FORCEPROP 2 LAST CUSTOM_TXT_CDS <XR_PAGE_TITLE>
J 0
(-7890 5250);
DISPLAY 0.638298 (-7890 5250);
PAINT PINK (-7890 5250);
DISPLAY INVISIBLE (-7890 5250);
FORCEPROP 0 LAST CDS_CON_LAST_MODIFIED Wed Mar 09 18:25:17 2022
J 0
(-1885 15);
DISPLAY INVISIBLE (-1885 15);
QUIT
